(kicad_pcb
	(version 20260206)
	(generator "pcbnew")
	(generator_version "10.0")
	(general
		(thickness 1.6)
		(legacy_teardrops no)
	)
	(paper "A4")
	(title_block
		(title "netronome-mezz — pcbd0082-001_rev01_jul9_a.brd")
		(comment 1 "Open CloudServer (Microsoft) / footprints 263-270 of 714")
	)
	(layers
		(0 "F.Cu" signal "TOP")
		(4 "In1.Cu" signal "02_GND")
		(6 "In2.Cu" signal "03_SIG")
		(8 "In3.Cu" signal "04_SIG")
		(10 "In4.Cu" signal "05_GND")
		(12 "In5.Cu" signal "06_PWR1")
		(14 "In6.Cu" signal "07_SIG")
		(16 "In7.Cu" signal "08_SIG")
		(18 "In8.Cu" signal "09_GND")
		(2 "B.Cu" signal "BOTTOM")
		(9 "F.Adhes" user "F.Adhesive")
		(11 "B.Adhes" user "B.Adhesive")
		(13 "F.Paste" user "Package Geometry/Pastemask Top")
		(15 "B.Paste" user "Package Geometry/Pastemask Bottom")
		(5 "F.SilkS" user "Ref Des/Silkscreen Top")
		(7 "B.SilkS" user "Ref Des/Silkscreen Bottom")
		(1 "F.Mask" user "Board Geometry/Soldermask Top")
		(3 "B.Mask" user "Board Geometry/Soldermask Bottom")
		(17 "Dwgs.User" user "User.Drawings")
		(19 "Cmts.User" user "User.Comments")
		(21 "Eco1.User" user "User.Eco1")
		(23 "Eco2.User" user "User.Eco2")
		(25 "Edge.Cuts" user "Board Geometry/Outline")
		(27 "Margin" user)
		(31 "F.CrtYd" user "Package Geometry/Place Bound Top")
		(29 "B.CrtYd" user "Package Geometry/Place Bound Bottom")
		(35 "F.Fab" user "Ref Des/Assembly Top")
		(33 "B.Fab" user "Ref Des/Assembly Bottom")
		(45 "User.4" user "COMPVAL_TYPE_BOTTOM")
	)
	(footprint ""
		(layer "F.Cu")
		(at 83.693 32.576414)
		(property "Reference" "R212"
			(at 0 0 0)
			(layer "F.SilkS")
			(hide yes)
			(effects
				(font
					(size 1.27 1.27)
				)
			)
		)
		(property "Value" "39.0"
			(at -0.148158 1.3462 90)
			(unlocked yes)
			(layer "F.Fab")
			(hide yes)
			(effects
				(font
					(size 1.27 0.9652)
					(thickness 0.000001)
				)
				(justify left)
			)
		)
		(property "Device Type" "REST0108"
			(at -0.148158 1.3462 90)
			(unlocked yes)
			(layer "F.Fab")
			(hide yes)
			(effects
				(font
					(size 1.27 0.9652)
					(thickness 0.000001)
				)
				(justify left)
			)
		)
		(duplicate_pad_numbers_are_jumpers no)
		(fp_poly
			(pts
				(xy 0.635 1.0668) (xy 0.635 -1.0668) (xy -0.635 -1.0668) (xy -0.635 1.0668)
			)
			(stroke
				(width 0)
				(type default)
			)
			(fill no)
			(layer "F.CrtYd")
		)
		(fp_line
			(start -0.254 -0.508)
			(end 0.254 -0.508)
			(stroke
				(width 0.0254)
				(type default)
			)
			(layer "F.Fab")
		)
		(fp_line
			(start -0.254 0.508)
			(end -0.254 -0.508)
			(stroke
				(width 0.0254)
				(type default)
			)
			(layer "F.Fab")
		)
		(fp_line
			(start 0.254 -0.508)
			(end 0.254 0.508)
			(stroke
				(width 0.0254)
				(type default)
			)
			(layer "F.Fab")
		)
		(fp_line
			(start 0.254 0.508)
			(end -0.254 0.508)
			(stroke
				(width 0.0254)
				(type default)
			)
			(layer "F.Fab")
		)
		(pad "1" smd rect
			(at 0 -0.4191)
			(size 0.508 0.5334)
			(layers "F.Cu" "F.Mask" "F.Paste")
			(net "DDR0_32A_A6")
		)
		(pad "2" smd rect
			(at 0 0.4191)
			(size 0.508 0.5334)
			(layers "F.Cu" "F.Mask" "F.Paste")
			(net "DDR_VTT")
		)
		(zone
			(layer "F.Cu")
			(hatch none 0.5)
			(connect_pads
				(clearance 0)
			)
			(min_thickness 0.25)
			(keepout
				(tracks not_allowed)
				(vias allowed)
				(pads allowed)
				(copperpour not_allowed)
				(footprints allowed)
			)
			(placement
				(enabled no)
				(sheetname "")
			)
			(fill
				(thermal_gap 0.5)
				(thermal_bridge_width 0.5)
				(island_removal_mode 0)
			)
			(polygon
				(pts
					(xy 83.7184 32.551014) (xy 83.7184 32.601814) (xy 83.6676 32.601814) (xy 83.6676 32.551014)
				)
			)
		)
	)
	(footprint ""
		(layer "F.Cu")
		(at 21.082 35.687 180)
		(property "Reference" "R67"
			(at 0 0 180)
			(layer "F.SilkS")
			(hide yes)
			(effects
				(font
					(size 1.27 1.27)
				)
			)
		)
		(property "Value" "4.75K"
			(at -0.148158 1.3462 270)
			(unlocked yes)
			(layer "F.Fab")
			(hide yes)
			(effects
				(font
					(size 1.27 0.9652)
					(thickness 0.000001)
				)
				(justify left)
			)
		)
		(property "Device Type" "REST4024"
			(at -0.148158 1.3462 270)
			(unlocked yes)
			(layer "F.Fab")
			(hide yes)
			(effects
				(font
					(size 1.27 0.9652)
					(thickness 0.000001)
				)
				(justify left)
			)
		)
		(duplicate_pad_numbers_are_jumpers no)
		(fp_poly
			(pts
				(xy 0.635 1.0668) (xy 0.635 -1.0668) (xy -0.635 -1.0668) (xy -0.635 1.0668)
			)
			(stroke
				(width 0)
				(type default)
			)
			(fill no)
			(layer "F.CrtYd")
		)
		(fp_line
			(start 0.254 0.508)
			(end -0.254 0.508)
			(stroke
				(width 0.0254)
				(type default)
			)
			(layer "F.Fab")
		)
		(fp_line
			(start 0.254 -0.508)
			(end 0.254 0.508)
			(stroke
				(width 0.0254)
				(type default)
			)
			(layer "F.Fab")
		)
		(fp_line
			(start -0.254 0.508)
			(end -0.254 -0.508)
			(stroke
				(width 0.0254)
				(type default)
			)
			(layer "F.Fab")
		)
		(fp_line
			(start -0.254 -0.508)
			(end 0.254 -0.508)
			(stroke
				(width 0.0254)
				(type default)
			)
			(layer "F.Fab")
		)
		(pad "1" smd rect
			(at 0 -0.4191 180)
			(size 0.508 0.5334)
			(layers "F.Cu" "F.Mask" "F.Paste")
			(net "VDD_3.3V")
		)
		(pad "2" smd rect
			(at 0 0.4191 180)
			(size 0.508 0.5334)
			(layers "F.Cu" "F.Mask" "F.Paste")
			(net "NFP_CPLD_PRGM_JTAG_TDO")
		)
		(zone
			(layer "F.Cu")
			(hatch none 0.5)
			(connect_pads
				(clearance 0)
			)
			(min_thickness 0.25)
			(keepout
				(tracks not_allowed)
				(vias allowed)
				(pads allowed)
				(copperpour not_allowed)
				(footprints allowed)
			)
			(placement
				(enabled no)
				(sheetname "")
			)
			(fill
				(thermal_gap 0.5)
				(thermal_bridge_width 0.5)
				(island_removal_mode 0)
			)
			(polygon
				(pts
					(xy 21.0566 35.7124) (xy 21.0566 35.6616) (xy 21.1074 35.6616) (xy 21.1074 35.7124)
				)
			)
		)
	)
	(footprint ""
		(layer "F.Cu")
		(at 74.244962 22.041993 90)
		(property "Reference" "C2"
			(at 0.933323 -2.108962 0)
			(unlocked yes)
			(layer "F.SilkS")
			(effects
				(font
					(size 0.7874 0.5842)
					(thickness 0.127)
				)
				(justify left)
			)
		)
		(property "Value" "22UF"
			(at -0.148158 1.7526 180)
			(unlocked yes)
			(layer "F.Fab")
			(hide yes)
			(effects
				(font
					(size 1.27 0.9652)
					(thickness 0.000001)
				)
				(justify left)
			)
		)
		(property "Device Type" "CAPC0063"
			(at -0.148158 1.7526 180)
			(unlocked yes)
			(layer "F.Fab")
			(hide yes)
			(effects
				(font
					(size 1.27 0.9652)
					(thickness 0.000001)
				)
				(justify left)
			)
		)
		(duplicate_pad_numbers_are_jumpers no)
		(fp_circle
			(center 0 0)
			(end 0 0.127)
			(stroke
				(width 0.2032)
				(type default)
			)
			(fill no)
			(layer "F.SilkS")
		)
		(fp_poly
			(pts
				(xy 0.7874 -1.6637) (xy -0.7874 -1.6637) (xy -0.7874 1.6637) (xy 0.7874 1.6637)
			)
			(stroke
				(width 0)
				(type default)
			)
			(fill no)
			(layer "F.CrtYd")
		)
		(fp_line
			(start 0.4064 -0.7874)
			(end 0.4064 0.8128)
			(stroke
				(width 0.0254)
				(type default)
			)
			(layer "F.Fab")
		)
		(fp_line
			(start -0.4064 -0.7874)
			(end 0.4064 -0.7874)
			(stroke
				(width 0.0254)
				(type default)
			)
			(layer "F.Fab")
		)
		(fp_line
			(start 0.4064 0.8128)
			(end -0.4064 0.8128)
			(stroke
				(width 0.0254)
				(type default)
			)
			(layer "F.Fab")
		)
		(fp_line
			(start -0.4064 0.8128)
			(end -0.4064 -0.7874)
			(stroke
				(width 0.0254)
				(type default)
			)
			(layer "F.Fab")
		)
		(pad "1" smd rect
			(at 0 -0.8001 90)
			(size 0.8636 0.9652)
			(layers "F.Cu" "F.Mask" "F.Paste")
			(net "DDR_VDDQ")
		)
		(pad "2" smd rect
			(at 0 0.8001 90)
			(size 0.8636 0.9652)
			(layers "F.Cu" "F.Mask" "F.Paste")
			(net "GND")
		)
		(zone
			(layer "F.Cu")
			(hatch none 0.5)
			(connect_pads
				(clearance 0)
			)
			(min_thickness 0.25)
			(keepout
				(tracks not_allowed)
				(vias allowed)
				(pads allowed)
				(copperpour not_allowed)
				(footprints allowed)
			)
			(placement
				(enabled no)
				(sheetname "")
			)
			(fill
				(thermal_gap 0.5)
				(thermal_bridge_width 0.5)
				(island_removal_mode 0)
			)
			(polygon
				(pts
					(xy 73.990962 22.105493) (xy 73.990962 21.978493) (xy 74.498962 21.978493) (xy 74.498962 22.105493)
				)
			)
		)
	)
	(footprint ""
		(layer "F.Cu")
		(at 28.575 42.545)
		(property "Reference" "R326"
			(at 0 0 0)
			(layer "F.SilkS")
			(hide yes)
			(effects
				(font
					(size 1.27 1.27)
				)
			)
		)
		(property "Value" "4.99K"
			(at -0.148158 1.3462 90)
			(unlocked yes)
			(layer "F.Fab")
			(hide yes)
			(effects
				(font
					(size 1.27 0.9652)
					(thickness 0.000001)
				)
				(justify left)
			)
		)
		(property "Device Type" "REST0014"
			(at -0.148158 1.3462 90)
			(unlocked yes)
			(layer "F.Fab")
			(hide yes)
			(effects
				(font
					(size 1.27 0.9652)
					(thickness 0.000001)
				)
				(justify left)
			)
		)
		(duplicate_pad_numbers_are_jumpers no)
		(fp_poly
			(pts
				(xy 0.635 1.0668) (xy 0.635 -1.0668) (xy -0.635 -1.0668) (xy -0.635 1.0668)
			)
			(stroke
				(width 0)
				(type default)
			)
			(fill no)
			(layer "F.CrtYd")
		)
		(fp_line
			(start -0.254 -0.508)
			(end 0.254 -0.508)
			(stroke
				(width 0.0254)
				(type default)
			)
			(layer "F.Fab")
		)
		(fp_line
			(start -0.254 0.508)
			(end -0.254 -0.508)
			(stroke
				(width 0.0254)
				(type default)
			)
			(layer "F.Fab")
		)
		(fp_line
			(start 0.254 -0.508)
			(end 0.254 0.508)
			(stroke
				(width 0.0254)
				(type default)
			)
			(layer "F.Fab")
		)
		(fp_line
			(start 0.254 0.508)
			(end -0.254 0.508)
			(stroke
				(width 0.0254)
				(type default)
			)
			(layer "F.Fab")
		)
		(pad "1" smd rect
			(at 0 -0.4191)
			(size 0.508 0.5334)
			(layers "F.Cu" "F.Mask" "F.Paste")
			(net "10N2498")
		)
		(pad "2" smd rect
			(at 0 0.4191)
			(size 0.508 0.5334)
			(layers "F.Cu" "F.Mask" "F.Paste")
			(net "10N2383")
		)
		(zone
			(layer "F.Cu")
			(hatch none 0.5)
			(connect_pads
				(clearance 0)
			)
			(min_thickness 0.25)
			(keepout
				(tracks not_allowed)
				(vias allowed)
				(pads allowed)
				(copperpour not_allowed)
				(footprints allowed)
			)
			(placement
				(enabled no)
				(sheetname "")
			)
			(fill
				(thermal_gap 0.5)
				(thermal_bridge_width 0.5)
				(island_removal_mode 0)
			)
			(polygon
				(pts
					(xy 28.6004 42.5196) (xy 28.6004 42.5704) (xy 28.5496 42.5704) (xy 28.5496 42.5196)
				)
			)
		)
	)
	(footprint ""
		(layer "F.Cu")
		(at 19.05 29.464 90)
		(property "Reference" "R63"
			(at 0 0 90)
			(layer "F.SilkS")
			(hide yes)
			(effects
				(font
					(size 1.27 1.27)
				)
			)
		)
		(property "Value" "4.75K"
			(at -0.148158 1.3462 180)
			(unlocked yes)
			(layer "F.Fab")
			(hide yes)
			(effects
				(font
					(size 1.27 0.9652)
					(thickness 0.000001)
				)
				(justify left)
			)
		)
		(property "Device Type" "REST4024"
			(at -0.148158 1.3462 180)
			(unlocked yes)
			(layer "F.Fab")
			(hide yes)
			(effects
				(font
					(size 1.27 0.9652)
					(thickness 0.000001)
				)
				(justify left)
			)
		)
		(duplicate_pad_numbers_are_jumpers no)
		(fp_poly
			(pts
				(xy 0.635 1.0668) (xy 0.635 -1.0668) (xy -0.635 -1.0668) (xy -0.635 1.0668)
			)
			(stroke
				(width 0)
				(type default)
			)
			(fill no)
			(layer "F.CrtYd")
		)
		(fp_line
			(start 0.254 -0.508)
			(end 0.254 0.508)
			(stroke
				(width 0.0254)
				(type default)
			)
			(layer "F.Fab")
		)
		(fp_line
			(start -0.254 -0.508)
			(end 0.254 -0.508)
			(stroke
				(width 0.0254)
				(type default)
			)
			(layer "F.Fab")
		)
		(fp_line
			(start 0.254 0.508)
			(end -0.254 0.508)
			(stroke
				(width 0.0254)
				(type default)
			)
			(layer "F.Fab")
		)
		(fp_line
			(start -0.254 0.508)
			(end -0.254 -0.508)
			(stroke
				(width 0.0254)
				(type default)
			)
			(layer "F.Fab")
		)
		(pad "1" smd rect
			(at 0 -0.4191 90)
			(size 0.508 0.5334)
			(layers "F.Cu" "F.Mask" "F.Paste")
			(net "EXT_3.3V")
		)
		(pad "2" smd rect
			(at 0 0.4191 90)
			(size 0.508 0.5334)
			(layers "F.Cu" "F.Mask" "F.Paste")
			(net "CPLD_PGRM_JTAG_TDI")
		)
		(zone
			(layer "F.Cu")
			(hatch none 0.5)
			(connect_pads
				(clearance 0)
			)
			(min_thickness 0.25)
			(keepout
				(tracks not_allowed)
				(vias allowed)
				(pads allowed)
				(copperpour not_allowed)
				(footprints allowed)
			)
			(placement
				(enabled no)
				(sheetname "")
			)
			(fill
				(thermal_gap 0.5)
				(thermal_bridge_width 0.5)
				(island_removal_mode 0)
			)
			(polygon
				(pts
					(xy 19.0246 29.4386) (xy 19.0754 29.4386) (xy 19.0754 29.4894) (xy 19.0246 29.4894)
				)
			)
		)
	)
	(footprint ""
		(layer "F.Cu")
		(at 1.778 31.75)
		(property "Reference" "TP47"
			(at -2.413 -1.75133 0)
			(unlocked yes)
			(layer "F.SilkS")
			(effects
				(font
					(size 0.7874 0.5842)
					(thickness 0.127)
				)
				(justify left)
			)
		)
		(property "Value" "*"
			(at -0.4826 -0.14732 0)
			(unlocked yes)
			(layer "F.Fab")
			(hide yes)
			(effects
				(font
					(size 1.27 0.9652)
					(thickness 0.000001)
				)
				(justify left)
			)
		)
		(property "Device Type" "TP_SMALL"
			(at -0.4826 -0.14732 0)
			(unlocked yes)
			(layer "F.Fab")
			(hide yes)
			(effects
				(font
					(size 1.27 0.9652)
					(thickness 0.000001)
				)
				(justify left)
			)
		)
		(duplicate_pad_numbers_are_jumpers no)
		(fp_line
			(start -0.8636 -0.8636)
			(end -0.8636 0.8636)
			(stroke
				(width 0.1524)
				(type default)
			)
			(layer "F.SilkS")
		)
		(fp_line
			(start -0.8636 0.8636)
			(end 0.8636 0.8636)
			(stroke
				(width 0.1524)
				(type default)
			)
			(layer "F.SilkS")
		)
		(fp_line
			(start 0.8636 -0.8636)
			(end -0.8636 -0.8636)
			(stroke
				(width 0.1524)
				(type default)
			)
			(layer "F.SilkS")
		)
		(fp_line
			(start 0.8636 0.8636)
			(end 0.8636 -0.8636)
			(stroke
				(width 0.1524)
				(type default)
			)
			(layer "F.SilkS")
		)
		(fp_poly
			(pts
				(xy -0.635 -0.635) (xy -0.635 0.635) (xy 0.635 0.635) (xy 0.635 -0.635)
			)
			(stroke
				(width 0)
				(type default)
			)
			(fill no)
			(layer "F.CrtYd")
		)
		(pad "1" smd rect
			(at 0 0)
			(size 1.27 1.27)
			(layers "F.Cu" "F.Mask" "F.Paste")
			(net "GND")
		)
	)
	(footprint ""
		(layer "F.Cu")
		(at 41.91 47.625)
		(property "Reference" "R101"
			(at -2.413 -1.24333 0)
			(unlocked yes)
			(layer "F.SilkS")
			(effects
				(font
					(size 0.7874 0.5842)
					(thickness 0.127)
				)
				(justify left)
			)
		)
		(property "Value" "4.75K"
			(at -0.148158 1.3462 90)
			(unlocked yes)
			(layer "F.Fab")
			(hide yes)
			(effects
				(font
					(size 1.27 0.9652)
					(thickness 0.000001)
				)
				(justify left)
			)
		)
		(property "Device Type" "REST4024"
			(at -0.148158 1.3462 90)
			(unlocked yes)
			(layer "F.Fab")
			(hide yes)
			(effects
				(font
					(size 1.27 0.9652)
					(thickness 0.000001)
				)
				(justify left)
			)
		)
		(duplicate_pad_numbers_are_jumpers no)
		(fp_poly
			(pts
				(xy 0.635 1.0668) (xy 0.635 -1.0668) (xy -0.635 -1.0668) (xy -0.635 1.0668)
			)
			(stroke
				(width 0)
				(type default)
			)
			(fill no)
			(layer "F.CrtYd")
		)
		(fp_line
			(start -0.254 -0.508)
			(end 0.254 -0.508)
			(stroke
				(width 0.0254)
				(type default)
			)
			(layer "F.Fab")
		)
		(fp_line
			(start -0.254 0.508)
			(end -0.254 -0.508)
			(stroke
				(width 0.0254)
				(type default)
			)
			(layer "F.Fab")
		)
		(fp_line
			(start 0.254 -0.508)
			(end 0.254 0.508)
			(stroke
				(width 0.0254)
				(type default)
			)
			(layer "F.Fab")
		)
		(fp_line
			(start 0.254 0.508)
			(end -0.254 0.508)
			(stroke
				(width 0.0254)
				(type default)
			)
			(layer "F.Fab")
		)
		(pad "1" smd rect
			(at 0 -0.4191)
			(size 0.508 0.5334)
			(layers "F.Cu" "F.Mask" "F.Paste")
			(net "GND")
		)
		(pad "2" smd rect
			(at 0 0.4191)
			(size 0.508 0.5334)
			(layers "F.Cu" "F.Mask" "F.Paste")
			(net "EXT_12.0V_PGOOD")
		)
		(zone
			(layer "F.Cu")
			(hatch none 0.5)
			(connect_pads
				(clearance 0)
			)
			(min_thickness 0.25)
			(keepout
				(tracks not_allowed)
				(vias allowed)
				(pads allowed)
				(copperpour not_allowed)
				(footprints allowed)
			)
			(placement
				(enabled no)
				(sheetname "")
			)
			(fill
				(thermal_gap 0.5)
				(thermal_bridge_width 0.5)
				(island_removal_mode 0)
			)
			(polygon
				(pts
					(xy 41.9354 47.5996) (xy 41.9354 47.6504) (xy 41.8846 47.6504) (xy 41.8846 47.5996)
				)
			)
		)
	)
	(footprint ""
		(layer "F.Cu")
		(at 42.799 53.1368)
		(property "Reference" "R279"
			(at -3.937 -0.15113 0)
			(unlocked yes)
			(layer "F.SilkS")
			(effects
				(font
					(size 0.7874 0.5842)
					(thickness 0.127)
				)
				(justify left)
			)
		)
		(property "Value" ""
			(at 0 0 0)
			(layer "F.Fab")
			(effects
				(font
					(size 1.27 1.27)
				)
			)
		)
		(duplicate_pad_numbers_are_jumpers no)
		(fp_line
			(start -0.0254 -0.127)
			(end 0.0254 -0.127)
			(stroke
				(width 0.1016)
				(type default)
			)
			(layer "F.SilkS")
		)
		(fp_line
			(start -0.0254 0.127)
			(end -0.0254 -0.127)
			(stroke
				(width 0.1016)
				(type default)
			)
			(layer "F.SilkS")
		)
		(fp_line
			(start 0.0254 -0.127)
			(end 0.0254 0.127)
			(stroke
				(width 0.1016)
				(type default)
			)
			(layer "F.SilkS")
		)
		(fp_line
			(start 0.0254 0.127)
			(end -0.0254 0.127)
			(stroke
				(width 0.1016)
				(type default)
			)
			(layer "F.SilkS")
		)
		(fp_poly
			(pts
				(xy 0.889 -0.4953) (xy 0.889 0.4953) (xy -0.889 0.4953) (xy -0.889 -0.4953)
			)
			(stroke
				(width 0)
				(type default)
			)
			(fill no)
			(layer "F.CrtYd")
		)
		(fp_line
			(start -0.508 -0.254)
			(end -0.508 0.254)
			(stroke
				(width 0.0254)
				(type default)
			)
			(layer "F.Fab")
		)
		(fp_line
			(start -0.508 0.254)
			(end 0.508 0.254)
			(stroke
				(width 0.0254)
				(type default)
			)
			(layer "F.Fab")
		)
		(fp_line
			(start 0.508 -0.254)
			(end -0.508 -0.254)
			(stroke
				(width 0.0254)
				(type default)
			)
			(layer "F.Fab")
		)
		(fp_line
			(start 0.508 0.254)
			(end 0.508 -0.254)
			(stroke
				(width 0.0254)
				(type default)
			)
			(layer "F.Fab")
		)
		(pad "1" smd rect
			(at -0.4699 0)
			(size 0.5334 0.508)
			(layers "F.Cu" "F.Mask" "F.Paste")
			(net "EXT_12.0V_THRESHOLD")
		)
		(pad "2" smd rect
			(at 0.4699 0)
			(size 0.5334 0.508)
			(layers "F.Cu" "F.Mask" "F.Paste")
			(net "EXT_12.0V")
		)
	)
)
